(kicad_pcb
	(version 20260206)
	(generator "pcbnew")
	(generator_version "10.0")
	(general
		(thickness 1.6)
		(legacy_teardrops no)
	)
	(paper "A4")
	(title_block
		(title "04192023_DAF0TMB3IC0_F0TG_MB_C_brd_V02_OCP.brd")
		(comment 1 "Grand Teton / footprints 2707-2712 of 8354")
	)
	(layers
		(0 "F.Cu" signal "TOP")
		(4 "In1.Cu" signal "GND")
		(6 "In2.Cu" signal "IN1")
		(8 "In3.Cu" signal "GND1")
		(10 "In4.Cu" signal "IN2")
		(12 "In5.Cu" signal "GND2")
		(14 "In6.Cu" signal "IN3")
		(16 "In7.Cu" signal "GND3")
		(18 "In8.Cu" signal "VCC")
		(20 "In9.Cu" signal "VCC1")
		(22 "In10.Cu" signal "GND4")
		(24 "In11.Cu" signal "IN4")
		(26 "In12.Cu" signal "GND5")
		(28 "In13.Cu" signal "IN5")
		(30 "In14.Cu" signal "GND6")
		(32 "In15.Cu" signal "IN6")
		(34 "In16.Cu" signal "GND7")
		(2 "B.Cu" signal "BOTTOM")
		(9 "F.Adhes" user "F.Adhesive")
		(11 "B.Adhes" user "B.Adhesive")
		(13 "F.Paste" user "Package Geometry/Pastemask Top")
		(15 "B.Paste" user "Package Geometry/Pastemask Bottom")
		(5 "F.SilkS" user "Ref Des/Silkscreen Top")
		(7 "B.SilkS" user "Ref Des/Silkscreen Bottom")
		(1 "F.Mask" user "Board Geometry/Soldermask Top")
		(3 "B.Mask" user "Board Geometry/Soldermask Bottom")
		(17 "Dwgs.User" user "User.Drawings")
		(19 "Cmts.User" user "User.Comments")
		(21 "Eco1.User" user "User.Eco1")
		(23 "Eco2.User" user "User.Eco2")
		(25 "Edge.Cuts" user "Board Geometry/Outline")
		(27 "Margin" user)
		(31 "F.CrtYd" user "Package Geometry/Place Bound Top")
		(29 "B.CrtYd" user "Package Geometry/Place Bound Bottom")
		(35 "F.Fab" user "Ref Des/Assembly Top")
		(33 "B.Fab" user "Ref Des/Assembly Bottom")
	)
	(footprint ""
		(layer "F.Cu")
		(at 110.235238 -39.40175 90)
		(property "Reference" "R6290"
			(at 0 0 90)
			(layer "F.SilkS")
			(hide yes)
			(effects
				(font
					(size 1.27 1.27)
				)
			)
		)
		(property "Value" ""
			(at 0 0 90)
			(layer "F.Fab")
			(effects
				(font
					(size 1.27 1.27)
				)
			)
		)
		(duplicate_pad_numbers_are_jumpers no)
		(fp_line
			(start 0.7874 -0.4064)
			(end 0.7874 0.4064)
			(stroke
				(width 0.1524)
				(type default)
			)
			(layer "F.SilkS")
		)
		(fp_line
			(start -0.7874 -0.4064)
			(end 0.7874 -0.4064)
			(stroke
				(width 0.1524)
				(type default)
			)
			(layer "F.SilkS")
		)
		(fp_line
			(start 0.7874 0.4064)
			(end -0.7874 0.4064)
			(stroke
				(width 0.1524)
				(type default)
			)
			(layer "F.SilkS")
		)
		(fp_line
			(start -0.7874 0.4064)
			(end -0.7874 -0.4064)
			(stroke
				(width 0.1524)
				(type default)
			)
			(layer "F.SilkS")
		)
		(fp_line
			(start -0.12065 -0.305054)
			(end -0.12065 -0.2794)
			(stroke
				(width 0.1)
				(type default)
			)
			(layer "F.Fab")
		)
		(fp_line
			(start -0.67945 -0.305054)
			(end -0.12065 -0.305054)
			(stroke
				(width 0.1)
				(type default)
			)
			(layer "F.Fab")
		)
		(fp_line
			(start 0.67945 -0.3048)
			(end 0.67945 0.3048)
			(stroke
				(width 0.1)
				(type default)
			)
			(layer "F.Fab")
		)
		(fp_line
			(start 0.12065 -0.3048)
			(end 0.67945 -0.3048)
			(stroke
				(width 0.1)
				(type default)
			)
			(layer "F.Fab")
		)
		(fp_line
			(start 0.12065 -0.2794)
			(end 0.12065 -0.3048)
			(stroke
				(width 0.1)
				(type default)
			)
			(layer "F.Fab")
		)
		(fp_line
			(start -0.12065 -0.2794)
			(end 0.12065 -0.2794)
			(stroke
				(width 0.1)
				(type default)
			)
			(layer "F.Fab")
		)
		(fp_line
			(start 0.120396 0.2794)
			(end -0.12065 0.2794)
			(stroke
				(width 0.1)
				(type default)
			)
			(layer "F.Fab")
		)
		(fp_line
			(start -0.12065 0.2794)
			(end -0.12065 0.3048)
			(stroke
				(width 0.1)
				(type default)
			)
			(layer "F.Fab")
		)
		(fp_line
			(start 0.67945 0.3048)
			(end 0.120396 0.3048)
			(stroke
				(width 0.1)
				(type default)
			)
			(layer "F.Fab")
		)
		(fp_line
			(start 0.120396 0.3048)
			(end 0.120396 0.2794)
			(stroke
				(width 0.1)
				(type default)
			)
			(layer "F.Fab")
		)
		(fp_line
			(start -0.12065 0.3048)
			(end -0.67945 0.3048)
			(stroke
				(width 0.1)
				(type default)
			)
			(layer "F.Fab")
		)
		(fp_line
			(start -0.67945 0.3048)
			(end -0.67945 -0.305054)
			(stroke
				(width 0.1)
				(type default)
			)
			(layer "F.Fab")
		)
		(pad "1" smd circle
			(at -0.40005 0 90)
			(size 0 0)
			(layers "F.Cu" "F.Mask" "F.Paste")
			(net "USB_HUB2_TI_GANGED_MRP_I2C_SLV_CFG0")
		)
		(pad "2" smd circle
			(at 0.40005 0 90)
			(size 0 0)
			(layers "F.Cu" "F.Mask" "F.Paste")
			(net "USB_HUB2_TI_GANGED")
		)
	)
	(footprint ""
		(layer "F.Cu")
		(at 169.121328 -388.366 90)
		(property "Reference" "C369"
			(at 0 0 90)
			(layer "F.SilkS")
			(hide yes)
			(effects
				(font
					(size 1.27 1.27)
				)
			)
		)
		(property "Value" ""
			(at 0 0 90)
			(layer "F.Fab")
			(effects
				(font
					(size 1.27 1.27)
				)
			)
		)
		(duplicate_pad_numbers_are_jumpers no)
		(fp_line
			(start 0.7874 -0.4064)
			(end 0.7874 0.4064)
			(stroke
				(width 0.1524)
				(type default)
			)
			(layer "F.SilkS")
		)
		(fp_line
			(start -0.7874 -0.4064)
			(end 0.7874 -0.4064)
			(stroke
				(width 0.1524)
				(type default)
			)
			(layer "F.SilkS")
		)
		(fp_line
			(start 0.7874 0.4064)
			(end -0.7874 0.4064)
			(stroke
				(width 0.1524)
				(type default)
			)
			(layer "F.SilkS")
		)
		(fp_line
			(start -0.7874 0.4064)
			(end -0.7874 -0.4064)
			(stroke
				(width 0.1524)
				(type default)
			)
			(layer "F.SilkS")
		)
		(fp_line
			(start -0.12065 -0.305054)
			(end -0.12065 -0.2794)
			(stroke
				(width 0.1)
				(type default)
			)
			(layer "F.Fab")
		)
		(fp_line
			(start -0.67945 -0.305054)
			(end -0.12065 -0.305054)
			(stroke
				(width 0.1)
				(type default)
			)
			(layer "F.Fab")
		)
		(fp_line
			(start 0.67945 -0.3048)
			(end 0.67945 0.3048)
			(stroke
				(width 0.1)
				(type default)
			)
			(layer "F.Fab")
		)
		(fp_line
			(start 0.12065 -0.3048)
			(end 0.67945 -0.3048)
			(stroke
				(width 0.1)
				(type default)
			)
			(layer "F.Fab")
		)
		(fp_line
			(start 0.12065 -0.2794)
			(end 0.12065 -0.3048)
			(stroke
				(width 0.1)
				(type default)
			)
			(layer "F.Fab")
		)
		(fp_line
			(start -0.12065 -0.2794)
			(end 0.12065 -0.2794)
			(stroke
				(width 0.1)
				(type default)
			)
			(layer "F.Fab")
		)
		(fp_line
			(start 0.120396 0.2794)
			(end -0.12065 0.2794)
			(stroke
				(width 0.1)
				(type default)
			)
			(layer "F.Fab")
		)
		(fp_line
			(start -0.12065 0.2794)
			(end -0.12065 0.3048)
			(stroke
				(width 0.1)
				(type default)
			)
			(layer "F.Fab")
		)
		(fp_line
			(start 0.67945 0.3048)
			(end 0.120396 0.3048)
			(stroke
				(width 0.1)
				(type default)
			)
			(layer "F.Fab")
		)
		(fp_line
			(start 0.120396 0.3048)
			(end 0.120396 0.2794)
			(stroke
				(width 0.1)
				(type default)
			)
			(layer "F.Fab")
		)
		(fp_line
			(start -0.12065 0.3048)
			(end -0.67945 0.3048)
			(stroke
				(width 0.1)
				(type default)
			)
			(layer "F.Fab")
		)
		(fp_line
			(start -0.67945 0.3048)
			(end -0.67945 -0.305054)
			(stroke
				(width 0.1)
				(type default)
			)
			(layer "F.Fab")
		)
		(pad "1" smd circle
			(at -0.40005 0 90)
			(size 0 0)
			(layers "F.Cu" "F.Mask" "F.Paste")
			(net "P1V8_CPU1_RT2_1A")
		)
		(pad "2" smd circle
			(at 0.40005 0 90)
			(size 0 0)
			(layers "F.Cu" "F.Mask" "F.Paste")
			(net "GND")
		)
	)
	(footprint ""
		(layer "F.Cu")
		(at 422.26611 -365.804196 90)
		(property "Reference" "PC200"
			(at 0 0 90)
			(layer "F.SilkS")
			(hide yes)
			(effects
				(font
					(size 1.27 1.27)
				)
			)
		)
		(property "Value" ""
			(at 0 0 90)
			(layer "F.Fab")
			(effects
				(font
					(size 1.27 1.27)
				)
			)
		)
		(duplicate_pad_numbers_are_jumpers no)
		(fp_line
			(start 0.7874 -0.4064)
			(end 0.7874 0.4064)
			(stroke
				(width 0.1524)
				(type default)
			)
			(layer "F.SilkS")
		)
		(fp_line
			(start -0.7874 -0.4064)
			(end 0.7874 -0.4064)
			(stroke
				(width 0.1524)
				(type default)
			)
			(layer "F.SilkS")
		)
		(fp_line
			(start 0.7874 0.4064)
			(end -0.7874 0.4064)
			(stroke
				(width 0.1524)
				(type default)
			)
			(layer "F.SilkS")
		)
		(fp_line
			(start -0.7874 0.4064)
			(end -0.7874 -0.4064)
			(stroke
				(width 0.1524)
				(type default)
			)
			(layer "F.SilkS")
		)
		(fp_line
			(start -0.12065 -0.305054)
			(end -0.12065 -0.2794)
			(stroke
				(width 0.1)
				(type default)
			)
			(layer "F.Fab")
		)
		(fp_line
			(start -0.67945 -0.305054)
			(end -0.12065 -0.305054)
			(stroke
				(width 0.1)
				(type default)
			)
			(layer "F.Fab")
		)
		(fp_line
			(start 0.67945 -0.3048)
			(end 0.67945 0.3048)
			(stroke
				(width 0.1)
				(type default)
			)
			(layer "F.Fab")
		)
		(fp_line
			(start 0.12065 -0.3048)
			(end 0.67945 -0.3048)
			(stroke
				(width 0.1)
				(type default)
			)
			(layer "F.Fab")
		)
		(fp_line
			(start 0.12065 -0.2794)
			(end 0.12065 -0.3048)
			(stroke
				(width 0.1)
				(type default)
			)
			(layer "F.Fab")
		)
		(fp_line
			(start -0.12065 -0.2794)
			(end 0.12065 -0.2794)
			(stroke
				(width 0.1)
				(type default)
			)
			(layer "F.Fab")
		)
		(fp_line
			(start 0.120396 0.2794)
			(end -0.12065 0.2794)
			(stroke
				(width 0.1)
				(type default)
			)
			(layer "F.Fab")
		)
		(fp_line
			(start -0.12065 0.2794)
			(end -0.12065 0.3048)
			(stroke
				(width 0.1)
				(type default)
			)
			(layer "F.Fab")
		)
		(fp_line
			(start 0.67945 0.3048)
			(end 0.120396 0.3048)
			(stroke
				(width 0.1)
				(type default)
			)
			(layer "F.Fab")
		)
		(fp_line
			(start 0.120396 0.3048)
			(end 0.120396 0.2794)
			(stroke
				(width 0.1)
				(type default)
			)
			(layer "F.Fab")
		)
		(fp_line
			(start -0.12065 0.3048)
			(end -0.67945 0.3048)
			(stroke
				(width 0.1)
				(type default)
			)
			(layer "F.Fab")
		)
		(fp_line
			(start -0.67945 0.3048)
			(end -0.67945 -0.305054)
			(stroke
				(width 0.1)
				(type default)
			)
			(layer "F.Fab")
		)
		(pad "1" smd circle
			(at -0.40005 0 90)
			(size 0 0)
			(layers "F.Cu" "F.Mask" "F.Paste")
			(net "PVDD11_S3_P0_VCC")
		)
		(pad "2" smd circle
			(at 0.40005 0 90)
			(size 0 0)
			(layers "F.Cu" "F.Mask" "F.Paste")
			(net "GND")
		)
	)
	(footprint ""
		(layer "F.Cu")
		(at 213.928198 -123.565412)
		(property "Reference" "R877"
			(at 0 0 0)
			(layer "F.SilkS")
			(hide yes)
			(effects
				(font
					(size 1.27 1.27)
				)
			)
		)
		(property "Value" ""
			(at 0 0 0)
			(layer "F.Fab")
			(effects
				(font
					(size 1.27 1.27)
				)
			)
		)
		(duplicate_pad_numbers_are_jumpers no)
		(fp_line
			(start -0.7874 -0.4064)
			(end 0.7874 -0.4064)
			(stroke
				(width 0.1524)
				(type default)
			)
			(layer "F.SilkS")
		)
		(fp_line
			(start -0.7874 0.4064)
			(end -0.7874 -0.4064)
			(stroke
				(width 0.1524)
				(type default)
			)
			(layer "F.SilkS")
		)
		(fp_line
			(start 0.7874 -0.4064)
			(end 0.7874 0.4064)
			(stroke
				(width 0.1524)
				(type default)
			)
			(layer "F.SilkS")
		)
		(fp_line
			(start 0.7874 0.4064)
			(end -0.7874 0.4064)
			(stroke
				(width 0.1524)
				(type default)
			)
			(layer "F.SilkS")
		)
		(fp_line
			(start -0.67945 -0.305054)
			(end -0.12065 -0.305054)
			(stroke
				(width 0.1)
				(type default)
			)
			(layer "F.Fab")
		)
		(fp_line
			(start -0.67945 0.3048)
			(end -0.67945 -0.305054)
			(stroke
				(width 0.1)
				(type default)
			)
			(layer "F.Fab")
		)
		(fp_line
			(start -0.12065 -0.305054)
			(end -0.12065 -0.2794)
			(stroke
				(width 0.1)
				(type default)
			)
			(layer "F.Fab")
		)
		(fp_line
			(start -0.12065 -0.2794)
			(end 0.12065 -0.2794)
			(stroke
				(width 0.1)
				(type default)
			)
			(layer "F.Fab")
		)
		(fp_line
			(start -0.12065 0.2794)
			(end -0.12065 0.3048)
			(stroke
				(width 0.1)
				(type default)
			)
			(layer "F.Fab")
		)
		(fp_line
			(start -0.12065 0.3048)
			(end -0.67945 0.3048)
			(stroke
				(width 0.1)
				(type default)
			)
			(layer "F.Fab")
		)
		(fp_line
			(start 0.120396 0.2794)
			(end -0.12065 0.2794)
			(stroke
				(width 0.1)
				(type default)
			)
			(layer "F.Fab")
		)
		(fp_line
			(start 0.120396 0.3048)
			(end 0.120396 0.2794)
			(stroke
				(width 0.1)
				(type default)
			)
			(layer "F.Fab")
		)
		(fp_line
			(start 0.12065 -0.3048)
			(end 0.67945 -0.3048)
			(stroke
				(width 0.1)
				(type default)
			)
			(layer "F.Fab")
		)
		(fp_line
			(start 0.12065 -0.2794)
			(end 0.12065 -0.3048)
			(stroke
				(width 0.1)
				(type default)
			)
			(layer "F.Fab")
		)
		(fp_line
			(start 0.67945 -0.3048)
			(end 0.67945 0.3048)
			(stroke
				(width 0.1)
				(type default)
			)
			(layer "F.Fab")
		)
		(fp_line
			(start 0.67945 0.3048)
			(end 0.120396 0.3048)
			(stroke
				(width 0.1)
				(type default)
			)
			(layer "F.Fab")
		)
		(pad "1" smd circle
			(at -0.40005 0)
			(size 0 0)
			(layers "F.Cu" "F.Mask" "F.Paste")
			(net "RST_PERST_OCP_SFF_BUF2_N")
		)
		(pad "2" smd circle
			(at 0.40005 0)
			(size 0 0)
			(layers "F.Cu" "F.Mask" "F.Paste")
			(net "RST_PERST0_OCP_SFF_N")
		)
	)
	(footprint ""
		(layer "F.Cu")
		(at 109.918754 -327.582276 180)
		(property "Reference" "PR226"
			(at 0 0 180)
			(layer "F.SilkS")
			(hide yes)
			(effects
				(font
					(size 1.27 1.27)
				)
			)
		)
		(property "Value" ""
			(at 0 0 180)
			(layer "F.Fab")
			(effects
				(font
					(size 1.27 1.27)
				)
			)
		)
		(duplicate_pad_numbers_are_jumpers no)
		(fp_line
			(start 0.7874 0.4064)
			(end -0.7874 0.4064)
			(stroke
				(width 0.1524)
				(type default)
			)
			(layer "F.SilkS")
		)
		(fp_line
			(start 0.7874 -0.4064)
			(end 0.7874 0.4064)
			(stroke
				(width 0.1524)
				(type default)
			)
			(layer "F.SilkS")
		)
		(fp_line
			(start -0.7874 0.4064)
			(end -0.7874 -0.4064)
			(stroke
				(width 0.1524)
				(type default)
			)
			(layer "F.SilkS")
		)
		(fp_line
			(start -0.7874 -0.4064)
			(end 0.7874 -0.4064)
			(stroke
				(width 0.1524)
				(type default)
			)
			(layer "F.SilkS")
		)
		(fp_line
			(start 0.67945 0.3048)
			(end 0.120396 0.3048)
			(stroke
				(width 0.1)
				(type default)
			)
			(layer "F.Fab")
		)
		(fp_line
			(start 0.67945 -0.3048)
			(end 0.67945 0.3048)
			(stroke
				(width 0.1)
				(type default)
			)
			(layer "F.Fab")
		)
		(fp_line
			(start 0.12065 -0.2794)
			(end 0.12065 -0.3048)
			(stroke
				(width 0.1)
				(type default)
			)
			(layer "F.Fab")
		)
		(fp_line
			(start 0.12065 -0.3048)
			(end 0.67945 -0.3048)
			(stroke
				(width 0.1)
				(type default)
			)
			(layer "F.Fab")
		)
		(fp_line
			(start 0.120396 0.3048)
			(end 0.120396 0.2794)
			(stroke
				(width 0.1)
				(type default)
			)
			(layer "F.Fab")
		)
		(fp_line
			(start 0.120396 0.2794)
			(end -0.12065 0.2794)
			(stroke
				(width 0.1)
				(type default)
			)
			(layer "F.Fab")
		)
		(fp_line
			(start -0.12065 0.3048)
			(end -0.67945 0.3048)
			(stroke
				(width 0.1)
				(type default)
			)
			(layer "F.Fab")
		)
		(fp_line
			(start -0.12065 0.2794)
			(end -0.12065 0.3048)
			(stroke
				(width 0.1)
				(type default)
			)
			(layer "F.Fab")
		)
		(fp_line
			(start -0.12065 -0.2794)
			(end 0.12065 -0.2794)
			(stroke
				(width 0.1)
				(type default)
			)
			(layer "F.Fab")
		)
		(fp_line
			(start -0.12065 -0.305054)
			(end -0.12065 -0.2794)
			(stroke
				(width 0.1)
				(type default)
			)
			(layer "F.Fab")
		)
		(fp_line
			(start -0.67945 0.3048)
			(end -0.67945 -0.305054)
			(stroke
				(width 0.1)
				(type default)
			)
			(layer "F.Fab")
		)
		(fp_line
			(start -0.67945 -0.305054)
			(end -0.12065 -0.305054)
			(stroke
				(width 0.1)
				(type default)
			)
			(layer "F.Fab")
		)
		(pad "1" smd circle
			(at -0.40005 0 180)
			(size 0 0)
			(layers "F.Cu" "F.Mask" "F.Paste")
			(net "VSENSE_VSS_SENSE_C_P1")
		)
		(pad "2" smd circle
			(at 0.40005 0 180)
			(size 0 0)
			(layers "F.Cu" "F.Mask" "F.Paste")
			(net "GND")
		)
	)
	(footprint ""
		(layer "F.Cu")
		(at 165.2016 -438.912)
		(property "Reference" "C1773"
			(at 0 0 0)
			(layer "F.SilkS")
			(hide yes)
			(effects
				(font
					(size 1.27 1.27)
				)
			)
		)
		(property "Value" ""
			(at 0 0 0)
			(layer "F.Fab")
			(effects
				(font
					(size 1.27 1.27)
				)
			)
		)
		(duplicate_pad_numbers_are_jumpers no)
		(fp_line
			(start -0.7874 -0.4064)
			(end 0.7874 -0.4064)
			(stroke
				(width 0.1524)
				(type default)
			)
			(layer "F.SilkS")
		)
		(fp_line
			(start -0.7874 0.4064)
			(end -0.7874 -0.4064)
			(stroke
				(width 0.1524)
				(type default)
			)
			(layer "F.SilkS")
		)
		(fp_line
			(start 0.7874 -0.4064)
			(end 0.7874 0.4064)
			(stroke
				(width 0.1524)
				(type default)
			)
			(layer "F.SilkS")
		)
		(fp_line
			(start 0.7874 0.4064)
			(end -0.7874 0.4064)
			(stroke
				(width 0.1524)
				(type default)
			)
			(layer "F.SilkS")
		)
		(fp_line
			(start -0.67945 -0.305054)
			(end -0.12065 -0.305054)
			(stroke
				(width 0.1)
				(type default)
			)
			(layer "F.Fab")
		)
		(fp_line
			(start -0.67945 0.3048)
			(end -0.67945 -0.305054)
			(stroke
				(width 0.1)
				(type default)
			)
			(layer "F.Fab")
		)
		(fp_line
			(start -0.12065 -0.305054)
			(end -0.12065 -0.2794)
			(stroke
				(width 0.1)
				(type default)
			)
			(layer "F.Fab")
		)
		(fp_line
			(start -0.12065 -0.2794)
			(end 0.12065 -0.2794)
			(stroke
				(width 0.1)
				(type default)
			)
			(layer "F.Fab")
		)
		(fp_line
			(start -0.12065 0.2794)
			(end -0.12065 0.3048)
			(stroke
				(width 0.1)
				(type default)
			)
			(layer "F.Fab")
		)
		(fp_line
			(start -0.12065 0.3048)
			(end -0.67945 0.3048)
			(stroke
				(width 0.1)
				(type default)
			)
			(layer "F.Fab")
		)
		(fp_line
			(start 0.120396 0.2794)
			(end -0.12065 0.2794)
			(stroke
				(width 0.1)
				(type default)
			)
			(layer "F.Fab")
		)
		(fp_line
			(start 0.120396 0.3048)
			(end 0.120396 0.2794)
			(stroke
				(width 0.1)
				(type default)
			)
			(layer "F.Fab")
		)
		(fp_line
			(start 0.12065 -0.3048)
			(end 0.67945 -0.3048)
			(stroke
				(width 0.1)
				(type default)
			)
			(layer "F.Fab")
		)
		(fp_line
			(start 0.12065 -0.2794)
			(end 0.12065 -0.3048)
			(stroke
				(width 0.1)
				(type default)
			)
			(layer "F.Fab")
		)
		(fp_line
			(start 0.67945 -0.3048)
			(end 0.67945 0.3048)
			(stroke
				(width 0.1)
				(type default)
			)
			(layer "F.Fab")
		)
		(fp_line
			(start 0.67945 0.3048)
			(end 0.120396 0.3048)
			(stroke
				(width 0.1)
				(type default)
			)
			(layer "F.Fab")
		)
		(pad "1" smd circle
			(at -0.40005 0)
			(size 0 0)
			(layers "F.Cu" "F.Mask" "F.Paste")
			(net "BIC_MONITER_ISO")
		)
		(pad "2" smd circle
			(at 0.40005 0)
			(size 0 0)
			(layers "F.Cu" "F.Mask" "F.Paste")
			(net "GND")
		)
	)
)
